(kicad_pcb
	(version 20260206)
	(generator "pcbnew")
	(generator_version "10.0")
	(general
		(thickness 1.6)
		(legacy_teardrops no)
	)
	(paper "A4")
	(title_block
		(title "4HDD Backplane_Layout.brd")
		(comment 1 "Tioga Pass / footprints 83-89 of 97")
	)
	(layers
		(0 "F.Cu" signal "TOP")
		(4 "In1.Cu" signal "L2GND")
		(6 "In2.Cu" signal "L3")
		(8 "In3.Cu" signal "L4")
		(10 "In4.Cu" signal "L5GND")
		(2 "B.Cu" signal "BOTTOM")
		(9 "F.Adhes" user "F.Adhesive")
		(11 "B.Adhes" user "B.Adhesive")
		(13 "F.Paste" user "Package Geometry/Pastemask Top")
		(15 "B.Paste" user "Package Geometry/Pastemask Bottom")
		(5 "F.SilkS" user "Ref Des/Silkscreen Top")
		(7 "B.SilkS" user "Ref Des/Silkscreen Bottom")
		(1 "F.Mask" user "Board Geometry/Soldermask Top")
		(3 "B.Mask" user "Board Geometry/Soldermask Bottom")
		(17 "Dwgs.User" user "User.Drawings")
		(19 "Cmts.User" user "User.Comments")
		(21 "Eco1.User" user "User.Eco1")
		(23 "Eco2.User" user "User.Eco2")
		(25 "Edge.Cuts" user "Board Geometry/Outline")
		(27 "Margin" user)
		(31 "F.CrtYd" user "Package Geometry/Place Bound Top")
		(29 "B.CrtYd" user "Package Geometry/Place Bound Bottom")
		(35 "F.Fab" user "Ref Des/Assembly Top")
		(33 "B.Fab" user "Ref Des/Assembly Bottom")
	)
	(footprint ""
		(layer "B.Cu")
		(at 70.485 -11.43 90)
		(property "Reference" "Q10"
			(at 0 0 90)
			(layer "B.SilkS")
			(hide yes)
			(effects
				(font
					(size 1.27 1.27)
				)
				(justify mirror)
			)
		)
		(property "Value" "FDS8878-G-GP"
			(at 3.707384 -1.5367 90)
			(unlocked yes)
			(layer "B.Fab")
			(hide yes)
			(effects
				(font
					(size 1.016 1.016)
					(thickness 0.1524)
				)
				(justify mirror)
			)
		)
		(property "Device Type" "SOIC8H69"
			(at 3.707384 -3.0607 90)
			(unlocked yes)
			(layer "B.Fab")
			(hide yes)
			(effects
				(font
					(size 1.016 1.016)
					(thickness 0.1524)
				)
				(justify mirror)
			)
		)
		(duplicate_pad_numbers_are_jumpers no)
		(fp_line
			(start 2.7432 -1.4224)
			(end 2.7432 1.4224)
			(stroke
				(width 0.1524)
				(type default)
			)
			(layer "B.SilkS")
		)
		(fp_line
			(start -2.1336 -1.4224)
			(end 2.7432 -1.4224)
			(stroke
				(width 0.1524)
				(type default)
			)
			(layer "B.SilkS")
		)
		(fp_line
			(start 2.7178 -0.508)
			(end 2.1844 -0.0508)
			(stroke
				(width 0.1524)
				(type default)
			)
			(layer "B.SilkS")
		)
		(fp_line
			(start 2.1844 -0.0508)
			(end 2.7178 0.508)
			(stroke
				(width 0.1524)
				(type default)
			)
			(layer "B.SilkS")
		)
		(fp_line
			(start 2.7432 1.4224)
			(end 2.6416 1.4224)
			(stroke
				(width 0.1524)
				(type default)
			)
			(layer "B.SilkS")
		)
		(fp_line
			(start 2.7432 1.4224)
			(end -2.1336 1.4224)
			(stroke
				(width 0.1524)
				(type default)
			)
			(layer "B.SilkS")
		)
		(fp_line
			(start -2.1336 1.4224)
			(end -2.1336 -1.4224)
			(stroke
				(width 0.1524)
				(type default)
			)
			(layer "B.SilkS")
		)
		(fp_line
			(start 2.6289 3.4417)
			(end 2.6289 1.4732)
			(stroke
				(width 0.381)
				(type default)
			)
			(layer "B.SilkS")
		)
		(fp_poly
			(pts
				(xy 2.2098 -1.4224) (xy 2.2098 1.4224) (xy -2.2098 1.4224) (xy -2.2098 -1.4224)
			)
			(stroke
				(width 0)
				(type default)
			)
			(fill yes)
			(layer "B.SilkS")
		)
		(fp_rect
			(start 2.450084 2.999994)
			(end -2.450084 -2.999994)
			(stroke
				(width 0)
				(type default)
			)
			(fill no)
			(layer "B.CrtYd")
		)
		(fp_poly
			(pts
				(xy 2.8194 3.6322) (xy 2.8194 -3.6322) (xy -2.8194 -3.6322) (xy -2.8194 1.18364) (xy -2.450084 1.18364)
				(xy -2.450084 -2.999994) (xy 2.450084 -2.999994) (xy 2.450084 2.999994) (xy -2.450084 2.999994)
				(xy -2.450084 1.18618) (xy -2.8194 1.18618) (xy -2.8194 3.6322)
			)
			(stroke
				(width 0)
				(type default)
			)
			(fill no)
			(layer "B.CrtYd")
		)
		(fp_rect
			(start 2.8194 3.6322)
			(end -2.8194 -3.6322)
			(stroke
				(width 0)
				(type default)
			)
			(fill no)
			(layer "B.Fab")
		)
		(pad "1" smd rect
			(at 1.905 2.54 270)
			(size 0.635 1.651)
			(layers "B.Cu" "B.Mask" "B.Paste")
			(net "P5V")
		)
		(pad "2" smd rect
			(at 0.635 2.54 270)
			(size 0.635 1.651)
			(layers "B.Cu" "B.Mask" "B.Paste")
			(net "P5V")
		)
		(pad "3" smd rect
			(at -0.635 2.54 270)
			(size 0.635 1.651)
			(layers "B.Cu" "B.Mask" "B.Paste")
			(net "P5V")
		)
		(pad "4" smd rect
			(at -1.905 2.54 270)
			(size 0.635 1.651)
			(layers "B.Cu" "B.Mask" "B.Paste")
			(net "PWR_EN_L_P5V")
		)
		(pad "5" smd rect
			(at -1.905 -2.54 270)
			(size 0.635 1.651)
			(layers "B.Cu" "B.Mask" "B.Paste")
			(net "P5V_SW_L")
		)
		(pad "6" smd rect
			(at -0.635 -2.54 270)
			(size 0.635 1.651)
			(layers "B.Cu" "B.Mask" "B.Paste")
			(net "P5V_SW_L")
		)
		(pad "7" smd rect
			(at 0.635 -2.54 270)
			(size 0.635 1.651)
			(layers "B.Cu" "B.Mask" "B.Paste")
			(net "P5V_SW_L")
		)
		(pad "8" smd rect
			(at 1.905 -2.54 270)
			(size 0.635 1.651)
			(layers "B.Cu" "B.Mask" "B.Paste")
			(net "P5V_SW_L")
		)
	)
	(footprint ""
		(layer "B.Cu")
		(at 86.36 -6.096 180)
		(property "Reference" "U13"
			(at 0 0 0)
			(layer "B.SilkS")
			(hide yes)
			(effects
				(font
					(size 1.27 1.27)
				)
				(justify mirror)
			)
		)
		(property "Value" "DMN63D1LDW-7-GP"
			(at 2.3622 -8.2042 180)
			(unlocked yes)
			(layer "B.Fab")
			(hide yes)
			(effects
				(font
					(size 1.016 1.016)
					(thickness 0.1524)
				)
				(justify mirror)
			)
		)
		(property "Device Type" "SOT-363H44"
			(at 2.3622 -10.1092 180)
			(unlocked yes)
			(layer "B.Fab")
			(hide yes)
			(effects
				(font
					(size 1.016 1.016)
					(thickness 0.1524)
				)
				(justify mirror)
			)
		)
		(duplicate_pad_numbers_are_jumpers no)
		(fp_line
			(start 1.4478 1.7018)
			(end -1.4478 1.7018)
			(stroke
				(width 0.1524)
				(type default)
			)
			(layer "B.SilkS")
		)
		(fp_line
			(start 1.4478 -1.7018)
			(end 1.4478 1.7018)
			(stroke
				(width 0.1524)
				(type default)
			)
			(layer "B.SilkS")
		)
		(fp_line
			(start 1.27 1.524)
			(end 1.27 0.6604)
			(stroke
				(width 0.4826)
				(type default)
			)
			(layer "B.SilkS")
		)
		(fp_line
			(start -1.4478 1.7018)
			(end -1.4478 -1.7018)
			(stroke
				(width 0.1524)
				(type default)
			)
			(layer "B.SilkS")
		)
		(fp_line
			(start -1.4478 -1.7018)
			(end 1.4478 -1.7018)
			(stroke
				(width 0.1524)
				(type default)
			)
			(layer "B.SilkS")
		)
		(fp_poly
			(pts
				(xy 1.524 -1.778) (xy -1.524 -1.778) (xy -1.524 1.778) (xy 1.524 1.778)
			)
			(stroke
				(width 0)
				(type default)
			)
			(fill no)
			(layer "B.CrtYd")
		)
		(fp_poly
			(pts
				(xy 1.524 -1.778) (xy -1.524 -1.778) (xy -1.524 1.778) (xy 1.524 1.778)
			)
			(stroke
				(width 0)
				(type default)
			)
			(fill no)
			(layer "B.Fab")
		)
		(pad "1" smd rect
			(at 0.65024 0.9398)
			(size 0.4064 1.016)
			(layers "B.Cu" "B.Mask" "B.Paste")
			(net "GND")
		)
		(pad "2" smd rect
			(at 0 0.9398)
			(size 0.4064 1.016)
			(layers "B.Cu" "B.Mask" "B.Paste")
			(net "PWR_EN_L_DELAY")
		)
		(pad "3" smd rect
			(at -0.65024 0.9398)
			(size 0.4064 1.016)
			(layers "B.Cu" "B.Mask" "B.Paste")
			(net "SW_SW_L_0")
		)
		(pad "4" smd rect
			(at -0.65024 -0.9398)
			(size 0.4064 1.016)
			(layers "B.Cu" "B.Mask" "B.Paste")
			(net "GND")
		)
		(pad "5" smd rect
			(at 0 -0.9398)
			(size 0.4064 1.016)
			(layers "B.Cu" "B.Mask" "B.Paste")
			(net "PWR_EN_D_2")
		)
		(pad "6" smd rect
			(at 0.65024 -0.9398)
			(size 0.4064 1.016)
			(layers "B.Cu" "B.Mask" "B.Paste")
			(net "PWR_EN_D_2")
		)
	)
	(footprint ""
		(layer "B.Cu")
		(at 81.565496 -14.402562 -90)
		(property "Reference" "PD1"
			(at 0 0 90)
			(layer "B.SilkS")
			(hide yes)
			(effects
				(font
					(size 1.27 1.27)
				)
				(justify mirror)
			)
		)
		(property "Value" "MMPZ5228BPT-GP"
			(at 0 -6.7818 270)
			(unlocked yes)
			(layer "B.Fab")
			(hide yes)
			(effects
				(font
					(size 1.016 1.016)
					(thickness 0.1524)
				)
				(justify mirror)
			)
		)
		(property "Device Type" "SOD323AKH40"
			(at 0 -8.6868 270)
			(unlocked yes)
			(layer "B.Fab")
			(hide yes)
			(effects
				(font
					(size 1.016 1.016)
					(thickness 0.1524)
				)
				(justify mirror)
			)
		)
		(duplicate_pad_numbers_are_jumpers no)
		(fp_line
			(start -0.889 2.159)
			(end 0.889 2.159)
			(stroke
				(width 0.1524)
				(type default)
			)
			(layer "B.SilkS")
		)
		(fp_line
			(start 0.889 2.159)
			(end 0.889 -1.9304)
			(stroke
				(width 0.1524)
				(type default)
			)
			(layer "B.SilkS")
		)
		(fp_line
			(start -0.762 2.0574)
			(end 0.762 2.0574)
			(stroke
				(width 0.508)
				(type default)
			)
			(layer "B.SilkS")
		)
		(fp_line
			(start -0.889 -1.9304)
			(end -0.889 2.159)
			(stroke
				(width 0.1524)
				(type default)
			)
			(layer "B.SilkS")
		)
		(fp_line
			(start 0.889 -1.9304)
			(end -0.889 -1.9304)
			(stroke
				(width 0.1524)
				(type default)
			)
			(layer "B.SilkS")
		)
		(fp_rect
			(start 1.016 2.3114)
			(end -1.016 -2.0066)
			(stroke
				(width 0)
				(type default)
			)
			(fill no)
			(layer "B.CrtYd")
		)
		(fp_poly
			(pts
				(xy 1.016 -2.0066) (xy -1.016 -2.0066) (xy -1.016 2.3114) (xy 1.016 2.3114)
			)
			(stroke
				(width 0)
				(type default)
			)
			(fill no)
			(layer "B.Fab")
		)
		(pad "A" smd rect
			(at 0 -1.143 90)
			(size 0.5588 1.016)
			(layers "B.Cu" "B.Mask" "B.Paste")
			(net "GND")
		)
		(pad "K" smd rect
			(at 0 1.143 90)
			(size 0.5588 1.016)
			(layers "B.Cu" "B.Mask" "B.Paste")
			(net "P5V_R_E1")
		)
	)
	(footprint ""
		(layer "B.Cu")
		(at 81.28 -54.991)
		(property "Reference" "U16"
			(at 0 0 0)
			(layer "B.SilkS")
			(hide yes)
			(effects
				(font
					(size 1.27 1.27)
				)
				(justify mirror)
			)
		)
		(property "Value" "SN74LVC1G08DCKR-GP"
			(at 2.3368 -8.6868 0)
			(unlocked yes)
			(layer "B.Fab")
			(hide yes)
			(effects
				(font
					(size 1.016 1.016)
					(thickness 0.1524)
				)
				(justify mirror)
			)
		)
		(property "Device Type" "SC70-5H44"
			(at 2.3114 -10.414 0)
			(unlocked yes)
			(layer "B.Fab")
			(hide yes)
			(effects
				(font
					(size 1.016 1.016)
					(thickness 0.1524)
				)
				(justify mirror)
			)
		)
		(duplicate_pad_numbers_are_jumpers no)
		(fp_line
			(start -1.3843 -1.8034)
			(end -1.3843 -1.1176)
			(stroke
				(width 0.3302)
				(type default)
			)
			(layer "B.SilkS")
		)
		(fp_line
			(start -1.27 -1.7018)
			(end -1.27 1.7018)
			(stroke
				(width 0.1524)
				(type default)
			)
			(layer "B.SilkS")
		)
		(fp_line
			(start -1.27 1.7018)
			(end 1.27 1.7018)
			(stroke
				(width 0.1524)
				(type default)
			)
			(layer "B.SilkS")
		)
		(fp_line
			(start -0.6604 -1.8034)
			(end -1.3843 -1.8034)
			(stroke
				(width 0.3302)
				(type default)
			)
			(layer "B.SilkS")
		)
		(fp_line
			(start 1.27 -1.7018)
			(end -1.27 -1.7018)
			(stroke
				(width 0.1524)
				(type default)
			)
			(layer "B.SilkS")
		)
		(fp_line
			(start 1.27 1.7018)
			(end 1.27 -1.7018)
			(stroke
				(width 0.1524)
				(type default)
			)
			(layer "B.SilkS")
		)
		(fp_rect
			(start 1.524 1.9558)
			(end -1.524 -1.9558)
			(stroke
				(width 0)
				(type default)
			)
			(fill no)
			(layer "B.CrtYd")
		)
		(fp_poly
			(pts
				(xy 1.524 -1.9558) (xy -1.524 -1.9558) (xy -1.524 1.9558) (xy 1.524 1.9558)
			)
			(stroke
				(width 0)
				(type default)
			)
			(fill no)
			(layer "B.Fab")
		)
		(pad "1" smd rect
			(at -0.65024 -0.8255 180)
			(size 0.4064 1.2192)
			(layers "B.Cu" "B.Mask" "B.Paste")
			(net "HBA_PRSNT0_N")
		)
		(pad "2" smd rect
			(at 0 -0.8255 180)
			(size 0.4064 1.2192)
			(layers "B.Cu" "B.Mask" "B.Paste")
			(net "HBA_PRSNT1_N")
		)
		(pad "3" smd rect
			(at 0.65024 -0.8255 180)
			(size 0.4064 1.2192)
			(layers "B.Cu" "B.Mask" "B.Paste")
			(net "GND")
		)
		(pad "4" smd rect
			(at 0.65024 0.8255 180)
			(size 0.4064 1.2192)
			(layers "B.Cu" "B.Mask" "B.Paste")
			(net "PWR_EN_R_N")
		)
		(pad "5" smd rect
			(at -0.65024 0.8255 180)
			(size 0.4064 1.2192)
			(layers "B.Cu" "B.Mask" "B.Paste")
			(net "P3V3")
		)
	)
	(footprint ""
		(layer "B.Cu")
		(at 75.0062 -40.3098 -90)
		(property "Reference" "C7"
			(at 0 0 90)
			(layer "B.SilkS")
			(hide yes)
			(effects
				(font
					(size 1.27 1.27)
				)
				(justify mirror)
			)
		)
		(property "Value" "SC10U25V6KX-1GP"
			(at 0.0762 -5.1308 270)
			(unlocked yes)
			(layer "B.Fab")
			(hide yes)
			(effects
				(font
					(size 1.016 1.016)
					(thickness 0.1524)
				)
				(justify mirror)
			)
		)
		(property "Device Type" "C1206H71"
			(at 0.127 -6.6548 270)
			(unlocked yes)
			(layer "B.Fab")
			(hide yes)
			(effects
				(font
					(size 1.016 1.016)
					(thickness 0.1524)
				)
				(justify mirror)
			)
		)
		(duplicate_pad_numbers_are_jumpers no)
		(fp_line
			(start -1.016 2.2352)
			(end 1.016 2.2352)
			(stroke
				(width 0.1524)
				(type default)
			)
			(layer "B.SilkS")
		)
		(fp_line
			(start 1.016 2.2352)
			(end 1.016 0.8382)
			(stroke
				(width 0.1524)
				(type default)
			)
			(layer "B.SilkS")
		)
		(fp_line
			(start -1.016 0.8382)
			(end -1.016 2.2352)
			(stroke
				(width 0.1524)
				(type default)
			)
			(layer "B.SilkS")
		)
		(fp_line
			(start 1.016 -0.8382)
			(end 1.016 -2.2352)
			(stroke
				(width 0.1524)
				(type default)
			)
			(layer "B.SilkS")
		)
		(fp_line
			(start -1.016 -2.2352)
			(end -1.016 -0.8382)
			(stroke
				(width 0.1524)
				(type default)
			)
			(layer "B.SilkS")
		)
		(fp_line
			(start 1.016 -2.2352)
			(end -1.016 -2.2352)
			(stroke
				(width 0.1524)
				(type default)
			)
			(layer "B.SilkS")
		)
		(fp_rect
			(start 1.0922 2.3114)
			(end -1.0922 -2.3114)
			(stroke
				(width 0)
				(type default)
			)
			(fill no)
			(layer "B.CrtYd")
		)
		(fp_poly
			(pts
				(xy -1.0922 -2.3114) (xy -1.0922 2.3114) (xy 1.0922 2.3114) (xy 1.0922 -2.3114)
			)
			(stroke
				(width 0)
				(type default)
			)
			(fill no)
			(layer "B.Fab")
		)
		(pad "1" smd rect
			(at 0 -1.397 90)
			(size 1.651 1.27)
			(layers "B.Cu" "B.Mask" "B.Paste")
			(net "P12V_SW_R")
		)
		(pad "2" smd rect
			(at 0 1.397 90)
			(size 1.651 1.27)
			(layers "B.Cu" "B.Mask" "B.Paste")
			(net "GND")
		)
	)
	(footprint ""
		(layer "B.Cu")
		(at 131.510532 -25.662636 -90)
		(property "Reference" "TC2"
			(at 0 0 90)
			(layer "B.SilkS")
			(hide yes)
			(effects
				(font
					(size 1.27 1.27)
				)
				(justify mirror)
			)
		)
		(property "Value" "SC22U25V5MX-GP"
			(at 0.0762 -6.1214 270)
			(unlocked yes)
			(layer "B.Fab")
			(hide yes)
			(effects
				(font
					(size 1.016 1.016)
					(thickness 0.1524)
				)
				(justify mirror)
			)
		)
		(property "Device Type" "C805H58"
			(at 0.0762 -8.1534 270)
			(unlocked yes)
			(layer "B.Fab")
			(hide yes)
			(effects
				(font
					(size 1.016 1.016)
					(thickness 0.1524)
				)
				(justify mirror)
			)
		)
		(duplicate_pad_numbers_are_jumpers no)
		(fp_line
			(start -0.635 0)
			(end 0.635 0)
			(stroke
				(width 0.508)
				(type default)
			)
			(layer "B.SilkS")
		)
		(fp_rect
			(start 0.9652 1.778)
			(end -0.9652 -1.778)
			(stroke
				(width 0)
				(type default)
			)
			(fill no)
			(layer "B.CrtYd")
		)
		(fp_poly
			(pts
				(xy 0.9652 -1.778) (xy -0.9652 -1.778) (xy -0.9652 1.778) (xy 0.9652 1.778)
			)
			(stroke
				(width 0)
				(type default)
			)
			(fill no)
			(layer "B.Fab")
		)
		(pad "1" smd rect
			(at 0 -0.9652 90)
			(size 1.397 1.143)
			(layers "B.Cu" "B.Mask" "B.Paste")
			(net "P5V")
		)
		(pad "2" smd rect
			(at 0 0.9652 90)
			(size 1.397 1.143)
			(layers "B.Cu" "B.Mask" "B.Paste")
			(net "GND")
		)
	)
	(footprint ""
		(layer "B.Cu")
		(at 78.7908 -11.7602 -90)
		(property "Reference" "C35"
			(at 0 0 90)
			(layer "B.SilkS")
			(hide yes)
			(effects
				(font
					(size 1.27 1.27)
				)
				(justify mirror)
			)
		)
		(property "Value" "SC2D2U25V3KX-GP"
			(at 0 -2.8194 270)
			(unlocked yes)
			(layer "B.Fab")
			(hide yes)
			(effects
				(font
					(size 1.016 1.016)
					(thickness 0.1524)
				)
				(justify mirror)
			)
		)
		(property "Device Type" "C603H38"
			(at 0 -4.3434 270)
			(unlocked yes)
			(layer "B.Fab")
			(hide yes)
			(effects
				(font
					(size 1.016 1.016)
					(thickness 0.1524)
				)
				(justify mirror)
			)
		)
		(duplicate_pad_numbers_are_jumpers no)
		(fp_line
			(start -0.508 0)
			(end 0.508 0)
			(stroke
				(width 0.2032)
				(type default)
			)
			(layer "B.SilkS")
		)
		(fp_rect
			(start 0.5842 1.3335)
			(end -0.5842 -1.3335)
			(stroke
				(width 0)
				(type default)
			)
			(fill no)
			(layer "B.CrtYd")
		)
		(fp_rect
			(start 0.5842 1.3335)
			(end -0.5842 -1.3335)
			(stroke
				(width 0)
				(type default)
			)
			(fill no)
			(layer "B.Fab")
		)
		(pad "1" smd custom
			(at 0 -0.762 90)
			(size 0.2159 0.2159)
			(layers "B.Cu" "B.Mask" "B.Paste")
			(net "CEXT_P5")
			(options
				(clearance outline)
				(anchor circle)
			)
			(primitives
				(gr_poly
					(pts
						(arc
							(start -0.3302 0.4318)
							(mid -0.402042 0.402042)
							(end -0.4318 0.3302)
						)
						(arc
							(start -0.4318 -0.3302)
							(mid -0.402042 -0.402042)
							(end -0.3302 -0.4318)
						)
						(arc
							(start 0.3302 -0.4318)
							(mid 0.402042 -0.402042)
							(end 0.4318 -0.3302)
						)
						(arc
							(start 0.4318 0.3302)
							(mid 0.402042 0.402042)
							(end 0.3302 0.4318)
						)
					)
					(width 0)
					(fill yes)
				)
			)
		)
		(pad "2" smd custom
			(at 0 0.762 90)
			(size 0.2159 0.2159)
			(layers "B.Cu" "B.Mask" "B.Paste")
			(net "GND")
			(options
				(clearance outline)
				(anchor circle)
			)
			(primitives
				(gr_poly
					(pts
						(arc
							(start -0.3302 0.4318)
							(mid -0.402042 0.402042)
							(end -0.4318 0.3302)
						)
						(arc
							(start -0.4318 -0.3302)
							(mid -0.402042 -0.402042)
							(end -0.3302 -0.4318)
						)
						(arc
							(start 0.3302 -0.4318)
							(mid 0.402042 -0.402042)
							(end 0.4318 -0.3302)
						)
						(arc
							(start 0.4318 0.3302)
							(mid 0.402042 0.402042)
							(end 0.3302 0.4318)
						)
					)
					(width 0)
					(fill yes)
				)
			)
		)
	)
)
